#ISCELL
  logical_power cad_note *
  *
#ISCELL
  pure_quanta quanta_title_block_c *
  *
#ISCELL
  standard offpage *
  page87_i1
#ISCELL
  standard offpage *
  page87_i10
#ISCELL
  standard tap *
  page87_i100
#ISCELL
  standard tap *
  page87_i101
#ISCELL
  standard tap *
  page87_i102
#ISCELL
  standard tap *
  page87_i103
#ISCELL
  standard offpage *
  page87_i104
#ISCELL
  standard tap *
  page87_i105
#ISCELL
  standard tap *
  page87_i106
#ISCELL
  standard tap *
  page87_i107
#ISCELL
  standard tap *
  page87_i108
#ISCELL
  standard tap *
  page87_i109
#ISCELL
  standard offpage *
  page87_i11
#ISCELL
  standard tap *
  page87_i110
#ISCELL
  standard tap *
  page87_i111
#ISCELL
  standard tap *
  page87_i112
#ISCELL
  standard tap *
  page87_i113
#ISCELL
  standard tap *
  page87_i114
#ISCELL
  standard tap *
  page87_i115
#ISCELL
  standard tap *
  page87_i116
#ISCELL
  standard tap *
  page87_i117
#ISCELL
  standard tap *
  page87_i118
#ISCELL
  logical_power universal_gnd *
  page87_i119
#ISCELL
  standard offpage *
  page87_i12
#CELL
  pure_quanta q_cap *
  page87_i120
#ISCELL
  logical_power vcc_core *
  page87_i121
#ISCELL
  standard offpage *
  page87_i122
#CELL
  pure_quanta q_cap *
  page87_i124
#ISCELL
  logical_power vcc_core *
  page87_i125
#ISCELL
  logical_power universal_gnd *
  page87_i126
#CELL
  pure_quanta q_cap *
  page87_i127
#ISCELL
  logical_power universal_gnd *
  page87_i128
#ISCELL
  standard tap *
  page87_i129
#ISCELL
  standard offpage *
  page87_i13
#ISCELL
  standard tap *
  page87_i130
#ISCELL
  standard tap *
  page87_i131
#ISCELL
  standard tap *
  page87_i132
#ISCELL
  standard tap *
  page87_i133
#ISCELL
  standard tap *
  page87_i134
#ISCELL
  standard tap *
  page87_i135
#ISCELL
  standard tap *
  page87_i136
#ISCELL
  standard tap *
  page87_i137
#ISCELL
  standard tap *
  page87_i138
#ISCELL
  standard tap *
  page87_i139
#ISCELL
  standard offpage *
  page87_i14
#ISCELL
  standard tap *
  page87_i140
#ISCELL
  standard tap *
  page87_i141
#ISCELL
  standard tap *
  page87_i142
#ISCELL
  standard tap *
  page87_i143
#ISCELL
  standard tap *
  page87_i144
#ISCELL
  standard tap *
  page87_i145
#ISCELL
  standard tap *
  page87_i146
#ISCELL
  standard tap *
  page87_i147
#ISCELL
  standard tap *
  page87_i148
#ISCELL
  standard tap *
  page87_i149
#ISCELL
  standard offpage *
  page87_i15
#ISCELL
  standard tap *
  page87_i150
#ISCELL
  standard tap *
  page87_i151
#ISCELL
  standard tap *
  page87_i152
#ISCELL
  standard tap *
  page87_i153
#ISCELL
  standard tap *
  page87_i154
#ISCELL
  standard tap *
  page87_i155
#ISCELL
  standard tap *
  page87_i156
#ISCELL
  standard tap *
  page87_i157
#ISCELL
  standard tap *
  page87_i158
#ISCELL
  standard tap *
  page87_i159
#ISCELL
  standard offpage *
  page87_i16
#ISCELL
  standard tap *
  page87_i160
#ISCELL
  standard tap *
  page87_i161
#ISCELL
  standard offpage *
  page87_i162
#ISCELL
  standard offpage *
  page87_i163
#ISCELL
  standard offpage *
  page87_i164
#ISCELL
  standard tap *
  page87_i165
#ISCELL
  standard tap *
  page87_i166
#ISCELL
  standard tap *
  page87_i167
#ISCELL
  standard tap *
  page87_i168
#ISCELL
  standard tap *
  page87_i169
#ISCELL
  standard offpage *
  page87_i17
#ISCELL
  standard tap *
  page87_i170
#ISCELL
  standard tap *
  page87_i171
#ISCELL
  standard offpage *
  page87_i172
#ISCELL
  standard offpage *
  page87_i173
#ISCELL
  logical_power vcc_core *
  page87_i174
#CELL
  pure_quanta sconn288_adr50017p087cc *
  page87_i175
#ISCELL
  logical_power universal_gnd *
  page87_i176
#ISCELL
  standard offpage *
  page87_i177
#CELL
  pure_quanta sconn288_adr50017p087cc *
  page87_i178
#ISCELL
  standard offpage *
  page87_i179
#ISCELL
  standard offpage *
  page87_i18
#CELL
  pure_quanta q_res *
  page87_i180
#ISCELL
  standard offpage *
  page87_i19
#ISCELL
  standard offpage *
  page87_i2
#ISCELL
  logical_power vcc_core *
  page87_i20
#ISCELL
  standard tap *
  page87_i21
#ISCELL
  standard tap *
  page87_i22
#ISCELL
  standard tap *
  page87_i23
#ISCELL
  standard tap *
  page87_i24
#ISCELL
  standard tap *
  page87_i25
#ISCELL
  standard tap *
  page87_i26
#ISCELL
  standard tap *
  page87_i27
#ISCELL
  standard tap *
  page87_i28
#ISCELL
  standard tap *
  page87_i29
#ISCELL
  standard offpage *
  page87_i3
#ISCELL
  standard tap *
  page87_i30
#ISCELL
  standard tap *
  page87_i31
#ISCELL
  standard tap *
  page87_i32
#ISCELL
  standard tap *
  page87_i33
#ISCELL
  standard tap *
  page87_i34
#ISCELL
  standard tap *
  page87_i35
#ISCELL
  standard tap *
  page87_i36
#ISCELL
  standard tap *
  page87_i37
#ISCELL
  standard tap *
  page87_i38
#ISCELL
  standard tap *
  page87_i39
#ISCELL
  standard tap *
  page87_i40
#ISCELL
  standard tap *
  page87_i41
#ISCELL
  standard tap *
  page87_i42
#ISCELL
  standard tap *
  page87_i43
#ISCELL
  logical_power universal_gnd *
  page87_i44
#CELL
  pure_quanta q_res *
  page87_i45
#CELL
  pure_quanta sconn288_adr50017p087cc *
  page87_i46
#ISCELL
  standard tap *
  page87_i47
#ISCELL
  standard tap *
  page87_i48
#ISCELL
  standard tap *
  page87_i49
#ISCELL
  standard offpage *
  page87_i5
#ISCELL
  standard tap *
  page87_i50
#ISCELL
  standard tap *
  page87_i51
#ISCELL
  standard tap *
  page87_i52
#ISCELL
  standard tap *
  page87_i53
#ISCELL
  standard tap *
  page87_i54
#ISCELL
  standard tap *
  page87_i55
#ISCELL
  standard tap *
  page87_i56
#ISCELL
  standard tap *
  page87_i57
#ISCELL
  standard tap *
  page87_i58
#ISCELL
  standard tap *
  page87_i59
#ISCELL
  standard offpage *
  page87_i6
#ISCELL
  standard tap *
  page87_i60
#ISCELL
  standard tap *
  page87_i61
#ISCELL
  standard tap *
  page87_i62
#ISCELL
  standard tap *
  page87_i63
#ISCELL
  standard tap *
  page87_i64
#ISCELL
  standard tap *
  page87_i65
#ISCELL
  standard tap *
  page87_i66
#ISCELL
  standard tap *
  page87_i67
#ISCELL
  standard tap *
  page87_i68
#ISCELL
  standard tap *
  page87_i69
#ISCELL
  standard offpage *
  page87_i7
#ISCELL
  standard tap *
  page87_i70
#ISCELL
  standard tap *
  page87_i71
#ISCELL
  standard tap *
  page87_i72
#ISCELL
  standard tap *
  page87_i73
#ISCELL
  standard tap *
  page87_i74
#ISCELL
  standard tap *
  page87_i75
#ISCELL
  standard tap *
  page87_i76
#ISCELL
  standard tap *
  page87_i77
#ISCELL
  standard tap *
  page87_i78
#ISCELL
  standard tap *
  page87_i79
#ISCELL
  standard offpage *
  page87_i8
#ISCELL
  standard tap *
  page87_i80
#ISCELL
  standard tap *
  page87_i81
#ISCELL
  standard tap *
  page87_i82
#ISCELL
  standard tap *
  page87_i83
#ISCELL
  standard tap *
  page87_i84
#ISCELL
  standard tap *
  page87_i85
#ISCELL
  standard tap *
  page87_i86
#ISCELL
  standard tap *
  page87_i87
#ISCELL
  standard tap *
  page87_i88
#ISCELL
  standard tap *
  page87_i89
#ISCELL
  standard offpage *
  page87_i9
#ISCELL
  standard tap *
  page87_i90
#ISCELL
  standard tap *
  page87_i91
#ISCELL
  standard tap *
  page87_i92
#ISCELL
  standard tap *
  page87_i93
#ISCELL
  standard tap *
  page87_i94
#ISCELL
  standard tap *
  page87_i95
#ISCELL
  standard tap *
  page87_i96
#ISCELL
  standard tap *
  page87_i97
#ISCELL
  standard tap *
  page87_i98
#ISCELL
  standard tap *
  page87_i99
